# S9S_MB_2U (Grand Teton) — schematic parts with pin connectivity, parts 1615–1615 of 6093; source: Cadence DE-HDL packaged netlist (pstxprt.dat, pstxnet.dat, pstchip.dat)

J22  SCONN288_ADR50017P087CC  SCONN288_ADR50017-P087CC IO  pkg DDR288S_1-1VXB  page 103
  1  VIN_BULK0  POWER  = P12V_S3_AUX_CPU1_NVDIMM
  2  RFU0  TRI  = TP_CHC_CPU1_DIMM2_FRU_0
  3  VIN_MGMT  POWER  = P3V3_AUX
  4  HSCL  IN  = I3C_SPD_DDRABCD_CPU1_LVC1_SCL_5
  5  HSDA  BI  = I3C_SPD_DDRABCD_CPU1_LVC1_SDA
  6  VSS0  POWER  = GND
  7  DQ0_A  BI  = M_C_CPU1_SA_DQ<0>
  8  VSS1  POWER  = GND
  9  DQ1_A  BI  = M_C_CPU1_SA_DQ<1>
  10  VSS2  POWER  = GND
  11  DQS0_A_T  BI  = M_C_CPU1_SA_DQS_DP<0>
  12  DQS0_A_C  BI  = M_C_CPU1_SA_DQS_DN<0>
  13  VSS3  POWER  = GND
  14  DQ4_A  BI  = M_C_CPU1_SA_DQ<4>
  15  VSS4  POWER  = GND
  16  DQ5_A  BI  = M_C_CPU1_SA_DQ<5>
  17  VSS5  POWER  = GND
  18  DQ8_A  BI  = M_C_CPU1_SA_DQ<8>
  19  VSS6  POWER  = GND
  20  DQ9_A  BI  = M_C_CPU1_SA_DQ<9>
  21  VSS7  POWER  = GND
  22  DQS1_A_T  BI  = M_C_CPU1_SA_DQS_DP<1>
  23  DQS1_A_C  BI  = M_C_CPU1_SA_DQS_DN<1>
  24  VSS8  POWER  = GND
  25  DQ12_A  BI  = M_C_CPU1_SA_DQ<12>
  26  VSS9  POWER  = GND
  27  DQ13_A  BI  = M_C_CPU1_SA_DQ<13>
  28  VSS10  POWER  = GND
  29  DQ16_A  BI  = M_C_CPU1_SA_DQ<16>
  30  VSS11  POWER  = GND
  31  DQ17_A  BI  = M_C_CPU1_SA_DQ<17>
  32  VSS12  POWER  = GND
  33  DQS2_A_T  BI  = M_C_CPU1_SA_DQS_DP<2>
  34  DQS2_A_C  BI  = M_C_CPU1_SA_DQS_DN<2>
  35  VSS13  POWER  = GND
  36  DQ20_A  BI  = M_C_CPU1_SA_DQ<20>
  37  VSS14  POWER  = GND
  38  DQ21_A  BI  = M_C_CPU1_SA_DQ<21>
  39  VSS15  POWER  = GND
  40  DQ24_A  BI  = M_C_CPU1_SA_DQ<24>
  41  VSS16  POWER  = GND
  42  DQ25_A  BI  = M_C_CPU1_SA_DQ<25>
  43  VSS17  POWER  = GND
  44  DQS3_A_T  BI  = M_C_CPU1_SA_DQS_DP<3>
  45  DQS3_A_C  BI  = M_C_CPU1_SA_DQS_DN<3>
  46  VSS18  POWER  = GND
  47  DQ28_A  BI  = M_C_CPU1_SA_DQ<28>
  48  VSS19  POWER  = GND
  49  DQ29_A  BI  = M_C_CPU1_SA_DQ<29>
  50  VSS20  POWER  = GND
  51  CB0_A  BI  = M_C_CPU1_SA_CB<0>
  52  VSS21  POWER  = GND
  53  CB1_A  BI  = M_C_CPU1_SA_CB<1>
  54  VSS22  POWER  = GND
  55  DQS4_A_T  BI  = M_C_CPU1_SA_DQS_DP<4>
  56  DQS4_A_C  BI  = M_C_CPU1_SA_DQS_DN<4>
  57  VSS23  POWER  = GND
  58  CB4_A  BI  = M_C_CPU1_SA_CB<4>
  59  VSS24  POWER  = GND
  60  CB5_A  BI  = M_C_CPU1_SA_CB<5>
  61  VSS25  POWER  = GND
  62  ALERT_N  OUT  = M_C_CPU1_ALERT_N
  63  VSS26  POWER  = GND
  64  CS0_A_N  IN  = M_C_CPU1_SA_CS_N<2>
  65  VSS27  POWER  = GND
  66  CA0_A  IN  = M_C_CPU1_SA_CA<0>
  67  VSS28  POWER  = GND
  68  CA2_A  IN  = M_C_CPU1_SA_CA<2>
  69  VSS29  POWER  = GND
  70  CA4_A  IN  = M_C_CPU1_SA_CA<4>
  71  VSS30  POWER  = GND
  72  CA6_A  IN  = M_C_CPU1_SA_CA<6>
  73  VSS31  POWER  = GND
  74  PAR_A  IN  = M_C_CPU1_SA_PAR
  75  VSS32  POWER  = GND
  76  CA0_B  IN  = M_C_CPU1_SB_CA<0>
  77  VSS33  POWER  = GND
  78  CA2_B  IN  = M_C_CPU1_SB_CA<2>
  79  VSS34  POWER  = GND
  80  CA4_B  IN  = M_C_CPU1_SB_CA<4>
  81  VSS35  POWER  = GND
  82  CA6_B  IN  = M_C_CPU1_SB_CA<6>
  83  VSS36  POWER  = GND
  84  CS0_B_N  IN  = M_C_CPU1_SB_CS_N<2>
  85  VSS37  POWER  = GND
  86  \lbd||rsp_a_n\  OUT  = M_C_CPU1_SA_RSP<1>
  87  \lbs||rsp_b_n\  OUT  = M_C_CPU1_SB_RSP<1>
  88  VSS38  POWER  = GND
  89  CB4_B  BI  = M_C_CPU1_SB_CB<4>
  90  VSS39  POWER  = GND
  91  CB5_B  BI  = M_C_CPU1_SB_CB<5>
  92  VSS40  POWER  = GND
  93  \dqs9_b_t||tdqs9_b_t||dbi4_b_n\  BI  = M_C_CPU1_SB_DQS_DP<9>
  94  \dqs9_b_c||tdqs9_b_c\  BI  = M_C_CPU1_SB_DQS_DN<9>
  95  VSS41  POWER  = GND
  96  CB0_B  BI  = M_C_CPU1_SB_CB<0>
  97  VSS42  POWER  = GND
  98  CB1_B  BI  = M_C_CPU1_SB_CB<1>
  99  VSS43  POWER  = GND
  100  DQ0_B  BI  = M_C_CPU1_SB_DQ<0>
  101  VSS44  POWER  = GND
  102  DQ1_B  BI  = M_C_CPU1_SB_DQ<1>
  103  VSS45  POWER  = GND
  104  DQS0_B_T  BI  = M_C_CPU1_SB_DQS_DP<0>
  105  DQS0_B_C  BI  = M_C_CPU1_SB_DQS_DN<0>
  106  VSS46  POWER  = GND
  107  DQ4_B  BI  = M_C_CPU1_SB_DQ<4>
  108  VSS47  POWER  = GND
  109  DQ5_B  BI  = M_C_CPU1_SB_DQ<5>
  110  VSS48  POWER  = GND
  111  DQ8_B  BI  = M_C_CPU1_SB_DQ<8>
  112  VSS49  POWER  = GND
  113  DQ9_B  BI  = M_C_CPU1_SB_DQ<9>
  114  VSS50  POWER  = GND
  115  DQS1_B_T  BI  = M_C_CPU1_SB_DQS_DP<1>
  116  DQS1_B_C  BI  = M_C_CPU1_SB_DQS_DN<1>
  117  VSS51  POWER  = GND
  118  DQ12_B  BI  = M_C_CPU1_SB_DQ<12>
  119  VSS52  POWER  = GND
  120  DQ13_B  BI  = M_C_CPU1_SB_DQ<13>
  121  VSS53  POWER  = GND
  122  DQ16_B  BI  = M_C_CPU1_SB_DQ<16>
  123  VSS54  POWER  = GND
  124  DQ17_B  BI  = M_C_CPU1_SB_DQ<17>
  125  VSS55  POWER  = GND
  126  DQS2_B_T  BI  = M_C_CPU1_SB_DQS_DP<2>
  127  DQS2_B_C  BI  = M_C_CPU1_SB_DQS_DN<2>
  128  VSS56  POWER  = GND
  129  DQ20_B  BI  = M_C_CPU1_SB_DQ<20>
  130  VSS57  POWER  = GND
  131  DQ21_B  BI  = M_C_CPU1_SB_DQ<21>
  132  VSS58  POWER  = GND
  133  DQ24_B  BI  = M_C_CPU1_SB_DQ<24>
  134  VSS59  POWER  = GND
  135  DQ25_B  BI  = M_C_CPU1_SB_DQ<25>
  136  VSS60  POWER  = GND
  137  DQS3_B_T  BI  = M_C_CPU1_SB_DQS_DP<3>
  138  DQS3_B_C  BI  = M_C_CPU1_SB_DQS_DN<3>
  139  VSS61  POWER  = GND
  140  DQ28_B  BI  = M_C_CPU1_SB_DQ<28>
  141  VSS62  POWER  = GND
  142  DQ29_B  BI  = M_C_CPU1_SB_DQ<29>
  143  VSS63  POWER  = GND
  144  RFU1  TRI  = TP_CHC_CPU1_DIMM2_FRU_1
  145  VIN_BULK1  POWER  = P12V_S3_AUX_CPU1_NVDIMM
  146  VIN_BULK2  POWER  = P12V_S3_AUX_CPU1_NVDIMM
  147  \pwr_good||fail_n\  BI  = PWRGD_CHC_CPU1_DIMM2
  148  HSA  IN  = PD_CHC_CPU1_DIMM2_SAA
  149  RFU2  TRI  = TP_CHC_CPU1_DIMM2_FRU_2
  150  RFU3  TRI  = TP_CHC_CPU1_DIMM2_FRU_3
  151  VSS64  POWER  = GND
  152  DQ2_A  BI  = M_C_CPU1_SA_DQ<2>
  153  VSS65  POWER  = GND
  154  DQ3_A  BI  = M_C_CPU1_SA_DQ<3>
  155  VSS66  POWER  = GND
  156  \dqs5_a_c||tdqs5_a_c||dqs5_a_t||tdqs5_a_t\  BI  = M_C_CPU1_SA_DQS_DN<5>
  157  \dqs5_a_t||tdqs5_a_t\  BI  = M_C_CPU1_SA_DQS_DP<5>
  158  VSS67  POWER  = GND
  159  DQ6_A  BI  = M_C_CPU1_SA_DQ<6>
  160  VSS68  POWER  = GND
  161  DQ7_A  BI  = M_C_CPU1_SA_DQ<7>
  162  VSS69  POWER  = GND
  163  DQ10_A  BI  = M_C_CPU1_SA_DQ<10>
  164  VSS70  POWER  = GND
  165  DQ11_A  BI  = M_C_CPU1_SA_DQ<11>
  166  VSS71  POWER  = GND
  167  \dqs6_a_c||tdqs6_a_c||dqs6_a_t||tdqs6_a_t\  BI  = M_C_CPU1_SA_DQS_DN<6>
  168  \dqs6_a_t||tdqs6_a_t\  BI  = M_C_CPU1_SA_DQS_DP<6>
  169  VSS72  POWER  = GND
  170  DQ14_A  BI  = M_C_CPU1_SA_DQ<14>
  171  VSS73  POWER  = GND
  172  DQ15_A  BI  = M_C_CPU1_SA_DQ<15>
  173  VSS74  POWER  = GND
  174  DQ18_A  BI  = M_C_CPU1_SA_DQ<18>
  175  VSS75  POWER  = GND
  176  DQ19_A  BI  = M_C_CPU1_SA_DQ<19>
  177  VSS76  POWER  = GND
  178  \dqs7_a_c||tdqs7_a_c\  BI  = M_C_CPU1_SA_DQS_DN<7>
  179  \dqs7_a_t||tdqs7_a_t\  BI  = M_C_CPU1_SA_DQS_DP<7>
  180  VSS77  POWER  = GND
  181  DQ22_A  BI  = M_C_CPU1_SA_DQ<22>
  182  VSS78  POWER  = GND
  183  DQ23_A  BI  = M_C_CPU1_SA_DQ<23>
  184  VSS79  POWER  = GND
  185  DQ26_A  BI  = M_C_CPU1_SA_DQ<26>
  186  VSS80  POWER  = GND
  187  DQ27_A  BI  = M_C_CPU1_SA_DQ<27>
  188  VSS81  POWER  = GND
  189  \dqs8_a_c||tdqs8_a_c\  BI  = M_C_CPU1_SA_DQS_DN<8>
  190  \dqs8_a_t||tdqs8_a_t\  BI  = M_C_CPU1_SA_DQS_DP<8>
  191  VSS82  POWER  = GND
  192  DQ30_A  BI  = M_C_CPU1_SA_DQ<30>
  193  VSS83  POWER  = GND
  194  DQ31_A  BI  = M_C_CPU1_SA_DQ<31>
  195  VSS84  POWER  = GND
  196  CB2_A  BI  = M_C_CPU1_SA_CB<2>
  197  VSS85  POWER  = GND
  198  CB3_A  BI  = M_C_CPU1_SA_CB<3>
  199  VSS86  POWER  = GND
  200  \dqs9_a_c||tdqs9_a_c\  BI  = M_C_CPU1_SA_DQS_DN<9>
  201  \dqs9_a_t||tdqs9_a_t\  BI  = M_C_CPU1_SA_DQS_DP<9>
  202  VSS87  POWER  = GND
  203  CB6_A  BI  = M_C_CPU1_SA_CB<6>
  204  VSS88  POWER  = GND
  205  CB7_A  BI  = M_C_CPU1_SA_CB<7>
  206  VSS89  POWER  = GND
  207  RESET_N  IN  = RST_M_CD_CPU1_FPGA_N
  208  VSS90  POWER  = GND
  209  CS1_A_N  IN  = M_C_CPU1_SA_CS_N<3>
  210  VSS91  POWER  = GND
  211  CA1_A  IN  = M_C_CPU1_SA_CA<1>
  212  VSS92  POWER  = GND
  213  CA3_A  IN  = M_C_CPU1_SA_CA<3>
  214  VSS93  POWER  = GND
  215  CA5_A  IN  = M_C_CPU1_SA_CA<5>
  216  VSS94  POWER  = GND
  217  CK_T  IN  = M_C_CPU1_CLK_DP<1>
  218  CK_C  IN  = M_C_CPU1_CLK_DN<1>
  219  VSS95  POWER  = GND
  220  RFU4  TRI  = TP_CHC_CPU1_DIMM2_FRU_4
  221  CA1_B  IN  = M_C_CPU1_SB_CA<1>
  222  VSS96  POWER  = GND
  223  CA3_B  IN  = M_C_CPU1_SB_CA<3>
  224  VSS97  POWER  = GND
  225  CA5_B  IN  = M_C_CPU1_SB_CA<5>
  226  VSS98  POWER  = GND
  227  PAR_B  IN  = M_C_CPU1_SB_PAR
  228  VSS99  POWER  = GND
  229  CS1_B_N  IN  = M_C_CPU1_SB_CS_N<3>
  230  VSS100  POWER  = GND
  231  RFU5  TRI  = TP_CHC_CPU1_DIMM2_FRU_5
  232  RFU6  TRI  = TP_CHC_CPU1_DIMM2_FRU_6
  233  VSS101  POWER  = GND
  234  CB6_B  BI  = M_C_CPU1_SB_CB<6>
  235  VSS102  POWER  = GND
  236  CB7_B  BI  = M_C_CPU1_SB_CB<7>
  237  VSS103  POWER  = GND
  238  DQS4_B_C  BI  = M_C_CPU1_SB_DQS_DN<4>
  239  DQS4_B_T  BI  = M_C_CPU1_SB_DQS_DP<4>
  240  VSS104  POWER  = GND
  241  CB2_B  BI  = M_C_CPU1_SB_CB<2>
  242  VSS105  POWER  = GND
  243  CB3_B  BI  = M_C_CPU1_SB_CB<3>
  244  VSS106  POWER  = GND
  245  DQ2_B  BI  = M_C_CPU1_SB_DQ<2>
  246  VSS107  POWER  = GND
  247  DQ3_B  BI  = M_C_CPU1_SB_DQ<3>
  248  VSS108  POWER  = GND
  249  \dqs5_b_c||tdqs5_b_c\  BI  = M_C_CPU1_SB_DQS_DN<5>
  250  \dqs5_b_t||tdqs5_b_t\  BI  = M_C_CPU1_SB_DQS_DP<5>
  251  VSS109  POWER  = GND
  252  DQ6_B  BI  = M_C_CPU1_SB_DQ<6>
  253  VSS110  POWER  = GND
  254  DQ7_B  BI  = M_C_CPU1_SB_DQ<7>
  255  VSS111  POWER  = GND
  256  DQ10_B  BI  = M_C_CPU1_SB_DQ<10>
  257  VSS112  POWER  = GND
  258  DQ11_B  BI  = M_C_CPU1_SB_DQ<11>
  259  VSS113  POWER  = GND
  260  \dqs6_b_c||tdqs6_b_c\  BI  = M_C_CPU1_SB_DQS_DN<6>
  261  \dqs6_b_t||tdqs6_b_t\  BI  = M_C_CPU1_SB_DQS_DP<6>
  262  VSS114  POWER  = GND
  263  DQ14_B  BI  = M_C_CPU1_SB_DQ<14>
  264  VSS115  POWER  = GND
  265  DQ15_B  BI  = M_C_CPU1_SB_DQ<15>
  266  VSS116  POWER  = GND
  267  DQ18_B  BI  = M_C_CPU1_SB_DQ<18>
  268  VSS117  POWER  = GND
  269  DQ19_B  BI  = M_C_CPU1_SB_DQ<19>
  270  VSS118  POWER  = GND
  271  \dqs7_b_c||tdqs7_b_c\  BI  = M_C_CPU1_SB_DQS_DN<7>
  272  \dqs7_b_t||tdqs7_b_t\  BI  = M_C_CPU1_SB_DQS_DP<7>
  273  VSS119  POWER  = GND
  274  DQ22_B  BI  = M_C_CPU1_SB_DQ<22>
  275  VSS120  POWER  = GND
  276  DQ23_B  BI  = M_C_CPU1_SB_DQ<23>
  277  VSS121  POWER  = GND
  278  DQ26_B  BI  = M_C_CPU1_SB_DQ<26>
  279  VSS122  POWER  = GND
  280  DQ27_B  BI  = M_C_CPU1_SB_DQ<27>
  281  VSS123  POWER  = GND
  282  \dqs8_b_c||tdqs8_b_c\  BI  = M_C_CPU1_SB_DQS_DN<8>
  283  \dqs8_b_t||tdqs8_b_t\  BI  = M_C_CPU1_SB_DQS_DP<8>
  284  VSS124  POWER  = GND
  285  DQ30_B  BI  = M_C_CPU1_SB_DQ<30>
  286  VSS125  POWER  = GND
  287  DQ31_B  BI  = M_C_CPU1_SB_DQ<31>
  288  VSS126  POWER  = GND
  G1  G1  POWER  = GND
  G2  G2  POWER  = GND
  G3  G3  POWER  = GND
